(kicad_pcb
	(version 20241229)
	(generator "pcbnew")
	(generator_version "9.0")
	(general
		(thickness 1.711)
		(legacy_teardrops no)
	)
	(paper "A4")
	(title_block
		(title "Antmicro Baseboard for Jetson AGX Thor")
		(date "2026-02-18")
		(rev "1.1.0")
		(company "Antmicro Ltd")
		(comment 1 "www.antmicro.com")
		(comment 9 "footprints 585-588 of 1170")
	)
	(layers
		(0 "F.Cu" signal)
		(4 "In1.Cu" signal)
		(6 "In2.Cu" signal)
		(8 "In3.Cu" signal)
		(10 "In4.Cu" jumper)
		(12 "In5.Cu" signal)
		(14 "In6.Cu" signal)
		(16 "In7.Cu" signal)
		(18 "In8.Cu" signal)
		(2 "B.Cu" signal)
		(9 "F.Adhes" user "F.Adhesive")
		(11 "B.Adhes" user "B.Adhesive")
		(13 "F.Paste" user)
		(15 "B.Paste" user)
		(5 "F.SilkS" user "F.Silkscreen")
		(7 "B.SilkS" user "B.Silkscreen")
		(1 "F.Mask" user)
		(3 "B.Mask" user)
		(17 "Dwgs.User" user "User.Drawings")
		(19 "Cmts.User" user "User.Comments")
		(21 "Eco1.User" user "User.Eco1")
		(23 "Eco2.User" user "User.Eco2")
		(25 "Edge.Cuts" user)
		(27 "Margin" user)
		(31 "F.CrtYd" user "F.Courtyard")
		(29 "B.CrtYd" user "B.Courtyard")
		(35 "F.Fab" user)
		(33 "B.Fab" user)
	)
	(footprint "antmicro-footprints:R_0402_1005Metric"
		(layer "F.Cu")
		(at 191.3 122.6 90)
		(descr "Resistor SMD 0402")
		(tags "resistor SMD 0402")
		(property "Reference" "R88"
			(at 7.1 -2.4 90)
			(layer "F.SilkS")
			(effects
				(font
					(size 0.7 0.7)
					(thickness 0.15)
				)
				(justify left bottom)
			)
		)
		(property "Value" "R_0R_0402"
			(at -1.011843 1.772047 90)
			(layer "F.Fab")
			(effects
				(font
					(size 0.7 0.7)
					(thickness 0.15)
				)
				(justify left bottom)
			)
		)
		(property "Datasheet" "https://industrial.panasonic.com/cdbs/www-data/pdf/RDA0000/AOA0000C301.pdf"
			(at 0 0 90)
			(layer "F.Fab")
			(hide yes)
			(effects
				(font
					(size 1.27 1.27)
					(thickness 0.15)
				)
			)
		)
		(property "Description" "SMD Chip Resistor, Jumper, 0 ohm, 100 mW, 0402 [1005 Metric], Thick Film, General Purpose"
			(at 0 0 90)
			(layer "F.Fab")
			(hide yes)
			(effects
				(font
					(size 1.27 1.27)
					(thickness 0.15)
				)
			)
		)
		(property "MPN" "ERJ2GE0R00X"
			(at 0 0 90)
			(unlocked yes)
			(layer "F.Fab")
			(hide yes)
			(effects
				(font
					(size 1 1)
					(thickness 0.15)
				)
			)
		)
		(property "Manufacturer" "Panasonic"
			(at 0 0 90)
			(unlocked yes)
			(layer "F.Fab")
			(hide yes)
			(effects
				(font
					(size 1 1)
					(thickness 0.15)
				)
			)
		)
		(property "License" "Apache-2.0"
			(at 0 0 90)
			(unlocked yes)
			(layer "F.Fab")
			(hide yes)
			(effects
				(font
					(size 1 1)
					(thickness 0.15)
				)
			)
		)
		(property "Author" "Antmicro"
			(at 0 0 90)
			(unlocked yes)
			(layer "F.Fab")
			(hide yes)
			(effects
				(font
					(size 1 1)
					(thickness 0.15)
				)
			)
		)
		(property "Val" "0R"
			(at 0 0 90)
			(unlocked yes)
			(layer "F.Fab")
			(hide yes)
			(effects
				(font
					(size 1 1)
					(thickness 0.15)
				)
			)
		)
		(property "Tolerance" "~"
			(at 0 0 90)
			(unlocked yes)
			(layer "F.Fab")
			(hide yes)
			(effects
				(font
					(size 1 1)
					(thickness 0.15)
				)
			)
		)
		(property "Current" "1A"
			(at 0 0 90)
			(unlocked yes)
			(layer "F.Fab")
			(hide yes)
			(effects
				(font
					(size 1 1)
					(thickness 0.15)
				)
			)
		)
		(sheetname "/USB Hub/")
		(sheetfile "usb_hub.kicad_sch")
		(attr smd exclude_from_pos_files exclude_from_bom dnp)
		(fp_rect
			(start -0.925 -0.47)
			(end 0.925 0.47)
			(stroke
				(width 0.05)
				(type default)
			)
			(fill no)
			(layer "F.CrtYd")
		)
		(fp_rect
			(start -0.5 -0.25)
			(end 0.5 0.25)
			(stroke
				(width 0.15)
				(type solid)
			)
			(fill no)
			(layer "F.Fab")
		)
		(fp_text user "License: Apache-2.0"
			(at -0.95 5.169 90)
			(layer "F.Fab")
			(effects
				(font
					(size 0.7 0.7)
					(thickness 0.15)
				)
				(justify left bottom)
			)
		)
		(fp_text user "Author: Antmicro"
			(at -0.95 4.169 90)
			(layer "F.Fab")
			(effects
				(font
					(size 0.7 0.7)
					(thickness 0.15)
				)
				(justify left bottom)
			)
		)
		(fp_text user "${REFERENCE}"
			(at -0.95 3.168 90)
			(layer "F.Fab")
			(effects
				(font
					(size 0.7 0.7)
					(thickness 0.15)
				)
				(justify left bottom)
			)
		)
		(pad "1" smd roundrect
			(at -0.48 0 90)
			(size 0.59 0.64)
			(layers "F.Cu" "F.Mask" "F.Paste")
			(roundrect_rratio 0.25)
			(net 925 "/USB Hub/HUB_SPI_D0")
			(pintype "passive")
		)
		(pad "2" smd roundrect
			(at 0.48 0 90)
			(size 0.59 0.64)
			(layers "F.Cu" "F.Mask" "F.Paste")
			(roundrect_rratio 0.25)
			(net 923 "/USB Debug, PD/SPI_{HUB_DEBUG}.MISO")
			(pintype "passive")
		)
	)
	(footprint "antmicro-footprints:C_0402_1005Metric"
		(layer "F.Cu")
		(at 61.05 85.95 90)
		(descr "Capacitor SMD 0402")
		(tags "capacitor SMD 0402")
		(property "Reference" "C157"
			(at 0.92 0.35 90)
			(layer "F.SilkS")
			(effects
				(font
					(size 0.7 0.7)
					(thickness 0.15)
				)
				(justify left bottom)
			)
		)
		(property "Value" "C_100n_0402"
			(at -1.022927 2.155213 90)
			(layer "F.Fab")
			(effects
				(font
					(size 0.7 0.7)
					(thickness 0.15)
				)
				(justify left bottom)
			)
		)
		(property "Datasheet" "https://www.murata.com/products/productdetail?partno=GRM155R61H104KE14%23"
			(at 0 0 90)
			(layer "F.Fab")
			(hide yes)
			(effects
				(font
					(size 1.27 1.27)
					(thickness 0.15)
				)
			)
		)
		(property "Description" "SMD Multilayer Ceramic Capacitor, 0.1 µF, 50 V, 0402 [1005 Metric], ± 10%, X5R, GRM Series"
			(at 0 0 90)
			(layer "F.Fab")
			(hide yes)
			(effects
				(font
					(size 1.27 1.27)
					(thickness 0.15)
				)
			)
		)
		(property "Manufacturer" "Murata"
			(at 0 0 90)
			(unlocked yes)
			(layer "F.Fab")
			(hide yes)
			(effects
				(font
					(size 1 1)
					(thickness 0.15)
				)
			)
		)
		(property "MPN" "GRM155R61H104KE14D"
			(at 0 0 90)
			(unlocked yes)
			(layer "F.Fab")
			(hide yes)
			(effects
				(font
					(size 1 1)
					(thickness 0.15)
				)
			)
		)
		(property "Val" "100n"
			(at 0 0 90)
			(unlocked yes)
			(layer "F.Fab")
			(hide yes)
			(effects
				(font
					(size 1 1)
					(thickness 0.15)
				)
			)
		)
		(property "License" "Apache-2.0"
			(at 0 0 90)
			(unlocked yes)
			(layer "F.Fab")
			(hide yes)
			(effects
				(font
					(size 1 1)
					(thickness 0.15)
				)
			)
		)
		(property "Author" "Antmicro"
			(at 0 0 90)
			(unlocked yes)
			(layer "F.Fab")
			(hide yes)
			(effects
				(font
					(size 1 1)
					(thickness 0.15)
				)
			)
		)
		(property "Voltage" "50V"
			(at 0 0 90)
			(unlocked yes)
			(layer "F.Fab")
			(hide yes)
			(effects
				(font
					(size 1 1)
					(thickness 0.15)
				)
			)
		)
		(property "Dielectric" "X5R"
			(at 0 0 90)
			(unlocked yes)
			(layer "F.Fab")
			(hide yes)
			(effects
				(font
					(size 1 1)
					(thickness 0.15)
				)
			)
		)
		(sheetname "/CSI/")
		(sheetfile "csi.kicad_sch")
		(attr smd)
		(fp_rect
			(start -0.925 -0.47)
			(end 0.925 0.47)
			(stroke
				(width 0.05)
				(type default)
			)
			(fill no)
			(layer "F.CrtYd")
		)
		(fp_line
			(start 0.504 -0.25)
			(end 0.504 0.248)
			(stroke
				(width 0.15)
				(type solid)
			)
			(layer "F.Fab")
		)
		(fp_line
			(start -0.494 -0.25)
			(end 0.504 -0.25)
			(stroke
				(width 0.15)
				(type solid)
			)
			(layer "F.Fab")
		)
		(fp_line
			(start 0.504 0.248)
			(end -0.494 0.248)
			(stroke
				(width 0.15)
				(type solid)
			)
			(layer "F.Fab")
		)
		(fp_line
			(start -0.494 0.248)
			(end -0.494 -0.25)
			(stroke
				(width 0.15)
				(type solid)
			)
			(layer "F.Fab")
		)
		(fp_text user "Author: Antmicro"
			(at -0.939 3.399 90)
			(layer "F.Fab")
			(effects
				(font
					(size 0.7 0.7)
					(thickness 0.15)
				)
				(justify left bottom)
			)
		)
		(fp_text user "${REFERENCE}"
			(at -0.939 4.599 90)
			(layer "F.Fab")
			(effects
				(font
					(size 0.7 0.7)
					(thickness 0.15)
				)
				(justify left bottom)
			)
		)
		(fp_text user "License: Apache-2.0"
			(at -0.939 5.799 90)
			(layer "F.Fab")
			(effects
				(font
					(size 0.7 0.7)
					(thickness 0.15)
				)
				(justify left bottom)
			)
		)
		(pad "1" smd roundrect
			(at -0.48 0 90)
			(size 0.59 0.64)
			(layers "F.Cu" "F.Mask" "F.Paste")
			(roundrect_rratio 0.25)
			(net 2 "+3V3")
			(pintype "passive")
		)
		(pad "2" smd roundrect
			(at 0.48 0 90)
			(size 0.59 0.64)
			(layers "F.Cu" "F.Mask" "F.Paste")
			(roundrect_rratio 0.25)
			(net 1 "GND")
			(pintype "passive")
		)
	)
	(footprint "antmicro-footprints:LED_0603_1608Metric_G"
		(layer "F.Cu")
		(at 68.750532 55.84 -90)
		(descr "LED SMD 0603 Green")
		(tags "LED SMD 0603 Green")
		(property "Reference" "D52"
			(at -0.84 3.850532 90)
			(layer "F.SilkS")
			(hide yes)
			(effects
				(font
					(size 0.7 0.7)
					(thickness 0.15)
				)
				(justify right top)
			)
		)
		(property "Value" "LED_G_0603_LTST-C190GKT"
			(at -0.001 1.599 90)
			(layer "F.Fab")
			(effects
				(font
					(size 0.7 0.7)
					(thickness 0.15)
				)
				(justify right top)
			)
		)
		(property "Datasheet" "https://media.digikey.com/pdf/Data%20Sheets/Lite-On%20PDFs/LTST-C190GKT.pdf"
			(at 0 0 90)
			(layer "F.Fab")
			(hide yes)
			(effects
				(font
					(size 1.27 1.27)
					(thickness 0.15)
				)
			)
		)
		(property "Description" "LED, Green, SMD, 0603, 20 mA, 2.1 V, 569 nm"
			(at 0 0 90)
			(layer "F.Fab")
			(hide yes)
			(effects
				(font
					(size 1.27 1.27)
					(thickness 0.15)
				)
			)
		)
		(property "MPN" "LTST-C190GKT"
			(at 0 0 270)
			(unlocked yes)
			(layer "F.Fab")
			(hide yes)
			(effects
				(font
					(size 1 1)
					(thickness 0.15)
				)
			)
		)
		(property "Manufacturer" "Lite-On"
			(at 0 0 270)
			(unlocked yes)
			(layer "F.Fab")
			(hide yes)
			(effects
				(font
					(size 1 1)
					(thickness 0.15)
				)
			)
		)
		(property "Color" "Green"
			(at 0 0 270)
			(unlocked yes)
			(layer "F.Fab")
			(hide yes)
			(effects
				(font
					(size 1 1)
					(thickness 0.15)
				)
			)
		)
		(property "Author" "Antmicro"
			(at 0 0 270)
			(unlocked yes)
			(layer "F.Fab")
			(hide yes)
			(effects
				(font
					(size 1 1)
					(thickness 0.15)
				)
			)
		)
		(property "License" "Apache-2.0"
			(at 0 0 270)
			(unlocked yes)
			(layer "F.Fab")
			(hide yes)
			(effects
				(font
					(size 1 1)
					(thickness 0.15)
				)
			)
		)
		(sheetname "/SoM_Power/")
		(sheetfile "som_power.kicad_sch")
		(attr smd)
		(fp_line
			(start 0.22 0.35)
			(end -0.22 0.35)
			(stroke
				(width 0.15)
				(type solid)
			)
			(layer "F.SilkS")
		)
		(fp_line
			(start -0.094672 0.201008)
			(end -0.094672 -0.198992)
			(stroke
				(width 0.1)
				(type solid)
			)
			(layer "F.SilkS")
		)
		(fp_line
			(start 0.105328 0.201008)
			(end -0.094672 0.001008)
			(stroke
				(width 0.1)
				(type solid)
			)
			(layer "F.SilkS")
		)
		(fp_line
			(start 0.105328 0.201008)
			(end 0.105328 -0.198992)
			(stroke
				(width 0.1)
				(type solid)
			)
			(layer "F.SilkS")
		)
		(fp_line
			(start -0.094672 0.001008)
			(end -0.24 0.001008)
			(stroke
				(width 0.1)
				(type solid)
			)
			(layer "F.SilkS")
		)
		(fp_line
			(start -0.094672 0.001008)
			(end 0.105328 -0.198992)
			(stroke
				(width 0.1)
				(type solid)
			)
			(layer "F.SilkS")
		)
		(fp_line
			(start 0.105328 0.001008)
			(end 0.24 0.001)
			(stroke
				(width 0.1)
				(type solid)
			)
			(layer "F.SilkS")
		)
		(fp_line
			(start -1.18 -0.319)
			(end -1.18 0.321)
			(stroke
				(width 0.15)
				(type solid)
			)
			(layer "F.SilkS")
		)
		(fp_line
			(start 0.22 -0.35)
			(end -0.22 -0.35)
			(stroke
				(width 0.15)
				(type solid)
			)
			(layer "F.SilkS")
		)
		(fp_rect
			(start 1.25 0.65)
			(end -1.25 -0.65)
			(stroke
				(width 0.05)
				(type solid)
			)
			(fill no)
			(layer "F.CrtYd")
		)
		(fp_line
			(start -0.199 0.2)
			(end -0.199 0.1)
			(stroke
				(width 0.15)
				(type solid)
			)
			(layer "F.Fab")
		)
		(fp_line
			(start 0.201 0.2)
			(end 0.201 0)
			(stroke
				(width 0.15)
				(type solid)
			)
			(layer "F.Fab")
		)
		(fp_line
			(start -0.199 0)
			(end -0.597 0)
			(stroke
				(width 0.15)
				(type solid)
			)
			(layer "F.Fab")
		)
		(fp_line
			(start -0.101 0)
			(end 0.201 0.2)
			(stroke
				(width 0.15)
				(type solid)
			)
			(layer "F.Fab")
		)
		(fp_line
			(start 0.201 0)
			(end 0.201 -0.202)
			(stroke
				(width 0.15)
				(type solid)
			)
			(layer "F.Fab")
		)
		(fp_line
			(start 0.599 0)
			(end 0.201 0)
			(stroke
				(width 0.15)
				(type solid)
			)
			(layer "F.Fab")
		)
		(fp_line
			(start -0.199 -0.202)
			(end -0.199 0.1)
			(stroke
				(width 0.15)
				(type solid)
			)
			(layer "F.Fab")
		)
		(fp_line
			(start 0.201 -0.202)
			(end -0.101 0)
			(stroke
				(width 0.15)
				(type solid)
			)
			(layer "F.Fab")
		)
		(fp_rect
			(start 0.848 0.4)
			(end -0.85 -0.402)
			(stroke
				(width 0.15)
				(type solid)
			)
			(fill no)
			(layer "F.Fab")
		)
		(fp_text user "${REFERENCE}"
			(at -1.4224 5.999 90)
			(layer "F.Fab")
			(effects
				(font
					(size 0.7 0.7)
					(thickness 0.15)
				)
				(justify right top)
			)
		)
		(fp_text user "License: Apache-2.0"
			(at -1.4224 3.599 90)
			(layer "F.Fab")
			(effects
				(font
					(size 0.7 0.7)
					(thickness 0.15)
				)
				(justify right top)
			)
		)
		(fp_text user "Author: Antmicro"
			(at -1.4224 4.799 90)
			(layer "F.Fab")
			(effects
				(font
					(size 0.7 0.7)
					(thickness 0.15)
				)
				(justify right top)
			)
		)
		(pad "1" smd roundrect
			(at -0.7 0 90)
			(size 0.8 1)
			(layers "F.Cu" "F.Mask" "F.Paste")
			(roundrect_rratio 0.2)
			(net 550 "Net-(D52-C)")
			(pinfunction "C")
			(pintype "passive")
		)
		(pad "2" smd roundrect
			(at 0.7 0 90)
			(size 0.8 1)
			(layers "F.Cu" "F.Mask" "F.Paste")
			(roundrect_rratio 0.2)
			(net 549 "Net-(D52-A)")
			(pinfunction "A")
			(pintype "passive")
		)
	)
	(footprint "antmicro-footprints:C_0402_1005Metric"
		(layer "F.Cu")
		(at 91.1 100.2)
		(descr "Capacitor SMD 0402")
		(tags "capacitor SMD 0402")
		(property "Reference" "C344"
			(at 1.1 0.5 0)
			(layer "F.SilkS")
			(effects
				(font
					(size 0.7 0.7)
					(thickness 0.15)
				)
				(justify left bottom)
			)
		)
		(property "Value" "C_100n_0402"
			(at -1.022927 2.155213 0)
			(layer "F.Fab")
			(effects
				(font
					(size 0.7 0.7)
					(thickness 0.15)
				)
				(justify left bottom)
			)
		)
		(property "Datasheet" "https://www.murata.com/products/productdetail?partno=GRM155R61H104KE14%23"
			(at 0 0 0)
			(layer "F.Fab")
			(hide yes)
			(effects
				(font
					(size 1.27 1.27)
					(thickness 0.15)
				)
			)
		)
		(property "Description" "SMD Multilayer Ceramic Capacitor, 0.1 µF, 50 V, 0402 [1005 Metric], ± 10%, X5R, GRM Series"
			(at 0 0 0)
			(layer "F.Fab")
			(hide yes)
			(effects
				(font
					(size 1.27 1.27)
					(thickness 0.15)
				)
			)
		)
		(property "Manufacturer" "Murata"
			(at 0 0 0)
			(unlocked yes)
			(layer "F.Fab")
			(hide yes)
			(effects
				(font
					(size 1 1)
					(thickness 0.15)
				)
			)
		)
		(property "MPN" "GRM155R61H104KE14D"
			(at 0 0 0)
			(unlocked yes)
			(layer "F.Fab")
			(hide yes)
			(effects
				(font
					(size 1 1)
					(thickness 0.15)
				)
			)
		)
		(property "Val" "100n"
			(at 0 0 0)
			(unlocked yes)
			(layer "F.Fab")
			(hide yes)
			(effects
				(font
					(size 1 1)
					(thickness 0.15)
				)
			)
		)
		(property "License" "Apache-2.0"
			(at 0 0 0)
			(unlocked yes)
			(layer "F.Fab")
			(hide yes)
			(effects
				(font
					(size 1 1)
					(thickness 0.15)
				)
			)
		)
		(property "Author" "Antmicro"
			(at 0 0 0)
			(unlocked yes)
			(layer "F.Fab")
			(hide yes)
			(effects
				(font
					(size 1 1)
					(thickness 0.15)
				)
			)
		)
		(property "Voltage" "50V"
			(at 0 0 0)
			(unlocked yes)
			(layer "F.Fab")
			(hide yes)
			(effects
				(font
					(size 1 1)
					(thickness 0.15)
				)
			)
		)
		(property "Dielectric" "X5R"
			(at 0 0 0)
			(unlocked yes)
			(layer "F.Fab")
			(hide yes)
			(effects
				(font
					(size 1 1)
					(thickness 0.15)
				)
			)
		)
		(sheetname "/SoM_IO2/")
		(sheetfile "som_io2.kicad_sch")
		(attr smd)
		(fp_poly
			(pts
				(xy -0.925 -0.47) (xy 0.925 -0.47) (xy 0.925 0.47) (xy -0.925 0.47)
			)
			(stroke
				(width 0.05)
				(type default)
			)
			(fill no)
			(layer "F.CrtYd")
		)
		(fp_line
			(start -0.494 -0.25)
			(end 0.504 -0.25)
			(stroke
				(width 0.15)
				(type solid)
			)
			(layer "F.Fab")
		)
		(fp_line
			(start -0.494 0.248)
			(end -0.494 -0.25)
			(stroke
				(width 0.15)
				(type solid)
			)
			(layer "F.Fab")
		)
		(fp_line
			(start 0.504 -0.25)
			(end 0.504 0.248)
			(stroke
				(width 0.15)
				(type solid)
			)
			(layer "F.Fab")
		)
		(fp_line
			(start 0.504 0.248)
			(end -0.494 0.248)
			(stroke
				(width 0.15)
				(type solid)
			)
			(layer "F.Fab")
		)
		(fp_text user "License: Apache-2.0"
			(at -0.939 5.799 0)
			(layer "F.Fab")
			(effects
				(font
					(size 0.7 0.7)
					(thickness 0.15)
				)
				(justify left bottom)
			)
		)
		(fp_text user "Author: Antmicro"
			(at -0.939 3.399 0)
			(layer "F.Fab")
			(effects
				(font
					(size 0.7 0.7)
					(thickness 0.15)
				)
				(justify left bottom)
			)
		)
		(fp_text user "${REFERENCE}"
			(at -0.939 4.599 0)
			(layer "F.Fab")
			(effects
				(font
					(size 0.7 0.7)
					(thickness 0.15)
				)
				(justify left bottom)
			)
		)
		(pad "1" smd roundrect
			(at -0.48 0)
			(size 0.59 0.64)
			(layers "F.Cu" "F.Mask" "F.Paste")
			(roundrect_rratio 0.25)
			(net 691 "/Expansion connector/DP3.TX0+")
			(pintype "passive")
		)
		(pad "2" smd roundrect
			(at 0.48 0)
			(size 0.59 0.64)
			(layers "F.Cu" "F.Mask" "F.Paste")
			(roundrect_rratio 0.25)
			(net 1264 "/SoM_IO2/DP3.TX0_C+")
			(pintype "passive")
		)
	)
)
